FILE_TYPE = MULTI_PHYS_TABLE;
PART 'STANDOFF'
{===========================================================================================================================}
:PACK_TYPE | MATERIAL |   PART_NUMBER   = EnvComp                  |  PART_NUMBER |    JEDEC_TYPE         | CLASS | HEIGHT     |COMPONENT_TYPE | LEAD_LENGTH | LPID   | SPEED_URL | Status |RPL| AML | Bus_Unit | Days ;
{===========================================================================================================================}
'TH1'      | 'SO'     | 'H72821-001'(!) = ''                       | 'H72821-001' | 'STANDOFF177'         | 'IO'  | '0.167 IN' | 'PSEUDO'      | '0.067'     | ''     | 'http://speed.intel.com:8081/speed/module/pdm/item/pdm_item_detail_direct.asp?item_cde=H72821-001&item_rev=01&url_param=unused' | '' | '' | '' | '' | '' 
'TH1'      | 'EMPTY'  | 'H72821-001'(!) = ''                       | 'H72821-001' | 'STANDOFF177'         | 'IO'  | '0.167 IN' | 'PSEUDO'      | '0.067'     | ''     | 'http://speed.intel.com:8081/speed/module/pdm/item/pdm_item_detail_direct.asp?item_cde=H72821-001&item_rev=01&url_param=unused' | '' | '' | '' | '' | '' 
END_PART
END.
